(kicad_pcb
	(version 20260206)
	(generator "pcbnew")
	(generator_version "10.0")
	(general
		(thickness 1.6)
		(legacy_teardrops no)
	)
	(paper "A4")
	(title_block
		(title "4HDD Backplane_Layout.brd")
		(comment 1 "Tioga Pass / footprint 50 of 97 (SATA1), pads 1-32 of 32")
	)
	(layers
		(0 "F.Cu" signal "TOP")
		(4 "In1.Cu" signal "L2GND")
		(6 "In2.Cu" signal "L3")
		(8 "In3.Cu" signal "L4")
		(10 "In4.Cu" signal "L5GND")
		(2 "B.Cu" signal "BOTTOM")
		(9 "F.Adhes" user "F.Adhesive")
		(11 "B.Adhes" user "B.Adhesive")
		(13 "F.Paste" user "Package Geometry/Pastemask Top")
		(15 "B.Paste" user "Package Geometry/Pastemask Bottom")
		(5 "F.SilkS" user "Ref Des/Silkscreen Top")
		(7 "B.SilkS" user "Ref Des/Silkscreen Bottom")
		(1 "F.Mask" user "Board Geometry/Soldermask Top")
		(3 "B.Mask" user "Board Geometry/Soldermask Bottom")
		(17 "Dwgs.User" user "User.Drawings")
		(19 "Cmts.User" user "User.Comments")
		(21 "Eco1.User" user "User.Eco1")
		(23 "Eco2.User" user "User.Eco2")
		(25 "Edge.Cuts" user "Board Geometry/Outline")
		(27 "Margin" user)
		(31 "F.CrtYd" user "Package Geometry/Place Bound Top")
		(29 "B.CrtYd" user "Package Geometry/Place Bound Bottom")
		(35 "F.Fab" user "Ref Des/Assembly Top")
		(33 "B.Fab" user "Ref Des/Assembly Bottom")
	)
	(footprint ""
		(layer "F.Cu")
		(at 107.145074 -53.01996 180)
		(property "Reference" "SATA1"
			(at 0 0 180)
			(layer "F.SilkS")
			(hide yes)
			(effects
				(font
					(size 1.27 1.27)
				)
			)
		)
		(property "Value" "FCI-CONN29-2R-GP-U"
			(at -35.2552 -14.1859 180)
			(unlocked yes)
			(layer "F.Fab")
			(hide yes)
			(effects
				(font
					(size 1.016 1.016)
					(thickness 0.1524)
				)
			)
		)
		(property "Device Type" "PREFIT-29P-458055-UH395"
			(at -35.2552 -15.7099 180)
			(unlocked yes)
			(layer "F.Fab")
			(hide yes)
			(effects
				(font
					(size 1.016 1.016)
					(thickness 0.1524)
				)
			)
		)
		(duplicate_pad_numbers_are_jumpers no)
		(pad "" np_thru_hole circle
			(at -23.95474 0 180)
			(size 0.254 0.254)
			(drill 1.3462)
			(layers "*.Cu" "*.Mask")
			(clearance 0.9017)
			(thermal_gap 0.9017)
		)
		(pad "30" thru_hole circle
			(at -26.07945 0 180)
			(size 2.3622 2.3622)
			(drill 1.949958)
			(layers "*.Cu" "*.Mask")
			(remove_unused_layers no)
			(net "Net_83")
			(clearance 0.1524)
			(thermal_gap 0.1524)
		)
		(pad "31" thru_hole circle
			(at 15.91945 0 180)
			(size 2.3622 2.3622)
			(drill 1.949958)
			(layers "*.Cu" "*.Mask")
			(remove_unused_layers no)
			(net "Net_74")
			(clearance 0.1524)
			(thermal_gap 0.1524)
		)
		(pad "P1" thru_hole circle
			(at -3.175 -1.27 180)
			(size 0.8636 0.8636)
			(drill 0.499872)
			(layers "*.Cu" "*.Mask")
			(remove_unused_layers no)
			(net "Net_79")
			(clearance 0.1778)
			(thermal_gap 0.1778)
		)
		(pad "P2" thru_hole circle
			(at -4.445 -1.27 180)
			(size 0.8636 0.8636)
			(drill 0.499872)
			(layers "*.Cu" "*.Mask")
			(remove_unused_layers no)
			(net "Net_81")
			(clearance 0.1778)
			(thermal_gap 0.1778)
		)
		(pad "P3" thru_hole circle
			(at -5.715 -1.27 180)
			(size 0.8636 0.8636)
			(drill 0.499872)
			(layers "*.Cu" "*.Mask")
			(remove_unused_layers no)
			(net "Net_80")
			(clearance 0.1778)
			(thermal_gap 0.1778)
		)
		(pad "P4" thru_hole circle
			(at -6.985 -1.27 180)
			(size 0.8636 0.8636)
			(drill 0.499872)
			(layers "*.Cu" "*.Mask")
			(remove_unused_layers no)
			(net "GND")
			(clearance 0.1778)
			(thermal_gap 0.1778)
		)
		(pad "P5" thru_hole circle
			(at -8.255 -1.27 180)
			(size 0.8636 0.8636)
			(drill 0.499872)
			(layers "*.Cu" "*.Mask")
			(remove_unused_layers no)
			(net "GND")
			(clearance 0.1778)
			(thermal_gap 0.1778)
		)
		(pad "P6" thru_hole circle
			(at -9.525 -1.27 180)
			(size 0.8636 0.8636)
			(drill 0.499872)
			(layers "*.Cu" "*.Mask")
			(remove_unused_layers no)
			(net "GND")
			(clearance 0.1778)
			(thermal_gap 0.1778)
		)
		(pad "P7" thru_hole circle
			(at -10.795 -1.27 180)
			(size 0.8636 0.8636)
			(drill 0.499872)
			(layers "*.Cu" "*.Mask")
			(remove_unused_layers no)
			(net "5V_PRE_0")
			(clearance 0.1778)
			(thermal_gap 0.1778)
		)
		(pad "P8" thru_hole circle
			(at -12.065 -1.27 180)
			(size 0.8636 0.8636)
			(drill 0.499872)
			(layers "*.Cu" "*.Mask")
			(remove_unused_layers no)
			(net "P5V_SW_R")
			(clearance 0.1778)
			(thermal_gap 0.1778)
		)
		(pad "P9" thru_hole circle
			(at -13.335 -1.27 180)
			(size 0.8636 0.8636)
			(drill 0.499872)
			(layers "*.Cu" "*.Mask")
			(remove_unused_layers no)
			(net "P5V_SW_R")
			(clearance 0.1778)
			(thermal_gap 0.1778)
		)
		(pad "P10" thru_hole circle
			(at -14.605 -1.27 180)
			(size 0.8636 0.8636)
			(drill 0.499872)
			(layers "*.Cu" "*.Mask")
			(remove_unused_layers no)
			(net "HBA_PRSNT0_N")
			(clearance 0.1778)
			(thermal_gap 0.1778)
		)
		(pad "P11" thru_hole circle
			(at -15.875 -1.27 180)
			(size 0.8636 0.8636)
			(drill 0.499872)
			(layers "*.Cu" "*.Mask")
			(remove_unused_layers no)
			(net "HDD_ACT_LED0")
			(clearance 0.1778)
			(thermal_gap 0.1778)
		)
		(pad "P12" thru_hole circle
			(at -17.145 -1.27 180)
			(size 0.8636 0.8636)
			(drill 0.499872)
			(layers "*.Cu" "*.Mask")
			(remove_unused_layers no)
			(net "GND")
			(clearance 0.1778)
			(thermal_gap 0.1778)
		)
		(pad "P13" thru_hole circle
			(at -18.415 -1.27 180)
			(size 0.8636 0.8636)
			(drill 0.499872)
			(layers "*.Cu" "*.Mask")
			(remove_unused_layers no)
			(net "12V_PRE_0")
			(clearance 0.1778)
			(thermal_gap 0.1778)
		)
		(pad "P14" thru_hole circle
			(at -19.685 -1.27 180)
			(size 0.8636 0.8636)
			(drill 0.499872)
			(layers "*.Cu" "*.Mask")
			(remove_unused_layers no)
			(net "P12V_SW_R")
			(clearance 0.1778)
			(thermal_gap 0.1778)
		)
		(pad "P15" thru_hole circle
			(at -20.955 -1.27 180)
			(size 0.8636 0.8636)
			(drill 0.499872)
			(layers "*.Cu" "*.Mask")
			(remove_unused_layers no)
			(net "P12V_SW_R")
			(clearance 0.1778)
			(thermal_gap 0.1778)
		)
		(pad "S1" thru_hole circle
			(at 10.795 -1.27 180)
			(size 0.8636 0.8636)
			(drill 0.499872)
			(layers "*.Cu" "*.Mask")
			(remove_unused_layers no)
			(net "GND")
			(clearance 0.1778)
			(thermal_gap 0.1778)
		)
		(pad "S2" thru_hole circle
			(at 9.525 -1.27 180)
			(size 0.8636 0.8636)
			(drill 0.499872)
			(layers "*.Cu" "*.Mask")
			(remove_unused_layers no)
			(net "HBA_MB_TX_P0")
			(clearance 0.1778)
			(thermal_gap 0.1778)
		)
		(pad "S3" thru_hole circle
			(at 8.255 -1.27 180)
			(size 0.8636 0.8636)
			(drill 0.499872)
			(layers "*.Cu" "*.Mask")
			(remove_unused_layers no)
			(net "HBA_MB_TX_N0")
			(clearance 0.1778)
			(thermal_gap 0.1778)
		)
		(pad "S4" thru_hole circle
			(at 6.985 -1.27 180)
			(size 0.8636 0.8636)
			(drill 0.499872)
			(layers "*.Cu" "*.Mask")
			(remove_unused_layers no)
			(net "GND")
			(clearance 0.1778)
			(thermal_gap 0.1778)
		)
		(pad "S5" thru_hole circle
			(at 5.715 -1.27 180)
			(size 0.8636 0.8636)
			(drill 0.499872)
			(layers "*.Cu" "*.Mask")
			(remove_unused_layers no)
			(net "HBA_MB_RX_N0")
			(clearance 0.1778)
			(thermal_gap 0.1778)
		)
		(pad "S6" thru_hole circle
			(at 4.445 -1.27 180)
			(size 0.8636 0.8636)
			(drill 0.499872)
			(layers "*.Cu" "*.Mask")
			(remove_unused_layers no)
			(net "HBA_MB_RX_P0")
			(clearance 0.1778)
			(thermal_gap 0.1778)
		)
		(pad "S7" thru_hole circle
			(at 3.175 -1.27 180)
			(size 0.8636 0.8636)
			(drill 0.499872)
			(layers "*.Cu" "*.Mask")
			(remove_unused_layers no)
			(net "GND")
			(clearance 0.1778)
			(thermal_gap 0.1778)
		)
		(pad "S8" thru_hole oval
			(at 2.4003 2.13995 180)
			(size 0.6096 0.8128)
			(drill 0.399796)
			(layers "*.Cu" "*.Mask")
			(remove_unused_layers no)
			(net "GND")
			(clearance 0.254)
			(thermal_gap 0.254)
		)
		(pad "S9" thru_hole oval
			(at 1.6002 2.13995 180)
			(size 0.6096 0.8128)
			(drill 0.399796)
			(layers "*.Cu" "*.Mask")
			(remove_unused_layers no)
			(net "Net_78")
			(clearance 0.254)
			(thermal_gap 0.254)
		)
		(pad "S10" thru_hole oval
			(at 0.8001 2.13995 180)
			(size 0.6096 0.8128)
			(drill 0.399796)
			(layers "*.Cu" "*.Mask")
			(remove_unused_layers no)
			(net "Net_77")
			(clearance 0.254)
			(thermal_gap 0.254)
		)
		(pad "S11" thru_hole oval
			(at 0 2.13995 180)
			(size 0.6096 0.8128)
			(drill 0.399796)
			(layers "*.Cu" "*.Mask")
			(remove_unused_layers no)
			(net "Net_40")
			(clearance 0.254)
			(thermal_gap 0.254)
		)
		(pad "S12" thru_hole oval
			(at -0.8001 2.13995 180)
			(size 0.6096 0.8128)
			(drill 0.399796)
			(layers "*.Cu" "*.Mask")
			(remove_unused_layers no)
			(net "Net_76")
			(clearance 0.254)
			(thermal_gap 0.254)
		)
		(pad "S13" thru_hole oval
			(at -1.6002 2.13995 180)
			(size 0.6096 0.8128)
			(drill 0.399796)
			(layers "*.Cu" "*.Mask")
			(remove_unused_layers no)
			(net "Net_75")
			(clearance 0.254)
			(thermal_gap 0.254)
		)
		(pad "S14" thru_hole oval
			(at -2.4003 2.13995 180)
			(size 0.6096 0.8128)
			(drill 0.399796)
			(layers "*.Cu" "*.Mask")
			(remove_unused_layers no)
			(net "GND")
			(clearance 0.254)
			(thermal_gap 0.254)
		)
	)
)
